# S9S_MB_2U (Grand Teton) — schematic netlist excerpt (pin names and nets, part order shuffled) for the footprints in the layout excerpt that follows; sources: Cadence DE-HDL packaged netlist, KiCad conversion of 03242023_DA0F0TMBIJ0_F0T_Motherboard_J_brd_V01_OCP.brd

C966  Q_CAP  10UF 6.3V 20% X6S  pkg C0402  page 74 : A = PVCCIN_CPU0 ; B = GND
C1561  Q_CAP  1UF 25V 10% X6S  pkg C0402  page 306 : A = U206_VDD ; B = GND

(kicad_pcb
	(version 20260206)
	(generator "pcbnew")
	(generator_version "10.0")
	(general
		(thickness 1.6)
		(legacy_teardrops no)
	)
	(paper "A4")
	(title_block
		(title "03242023_DA0F0TMBIJ0_F0T_Motherboard_J_brd_V01_OCP.brd")
		(comment 1 "Grand Teton / footprints 1437-1438 of 6105")
	)
	(layers
		(0 "F.Cu" signal "TOP")
		(4 "In1.Cu" signal "GND")
		(6 "In2.Cu" signal "IN1")
		(8 "In3.Cu" signal "GND1")
		(10 "In4.Cu" signal "IN2")
		(12 "In5.Cu" signal "GND2")
		(14 "In6.Cu" signal "IN3")
		(16 "In7.Cu" signal "GND3")
		(18 "In8.Cu" signal "VCC")
		(20 "In9.Cu" signal "VCC1")
		(22 "In10.Cu" signal "GND4")
		(24 "In11.Cu" signal "IN4")
		(26 "In12.Cu" signal "GND5")
		(28 "In13.Cu" signal "IN5")
		(30 "In14.Cu" signal "GND6")
		(32 "In15.Cu" signal "IN6")
		(34 "In16.Cu" signal "GND7")
		(2 "B.Cu" signal "BOTTOM")
		(9 "F.Adhes" user "F.Adhesive")
		(11 "B.Adhes" user "B.Adhesive")
		(13 "F.Paste" user "Package Geometry/Pastemask Top")
		(15 "B.Paste" user "Package Geometry/Pastemask Bottom")
		(5 "F.SilkS" user "Ref Des/Silkscreen Top")
		(7 "B.SilkS" user "Ref Des/Silkscreen Bottom")
		(1 "F.Mask" user "Board Geometry/Soldermask Top")
		(3 "B.Mask" user "Board Geometry/Soldermask Bottom")
		(17 "Dwgs.User" user "User.Drawings")
		(19 "Cmts.User" user "User.Comments")
		(21 "Eco1.User" user "User.Eco1")
		(23 "Eco2.User" user "User.Eco2")
		(25 "Edge.Cuts" user "Board Geometry/Outline")
		(27 "Margin" user)
		(31 "F.CrtYd" user "Package Geometry/Place Bound Top")
		(29 "B.CrtYd" user "Package Geometry/Place Bound Bottom")
		(35 "F.Fab" user "Ref Des/Assembly Top")
		(33 "B.Fab" user "Ref Des/Assembly Bottom")
	)
	(footprint ""
		(layer "F.Cu")
		(at 220.087444 -100.23348)
		(property "Reference" "C1561"
			(at 0 0 0)
			(layer "F.SilkS")
			(hide yes)
			(effects
				(font
					(size 1.27 1.27)
				)
			)
		)
		(property "Value" ""
			(at 0 0 0)
			(layer "F.Fab")
			(effects
				(font
					(size 1.27 1.27)
				)
			)
		)
		(duplicate_pad_numbers_are_jumpers no)
		(fp_line
			(start -0.7874 -0.4064)
			(end 0.7874 -0.4064)
			(stroke
				(width 0.1524)
				(type default)
			)
			(layer "F.SilkS")
		)
		(fp_line
			(start -0.7874 0.4064)
			(end -0.7874 -0.4064)
			(stroke
				(width 0.1524)
				(type default)
			)
			(layer "F.SilkS")
		)
		(fp_line
			(start 0.7874 -0.4064)
			(end 0.7874 0.4064)
			(stroke
				(width 0.1524)
				(type default)
			)
			(layer "F.SilkS")
		)
		(fp_line
			(start 0.7874 0.4064)
			(end -0.7874 0.4064)
			(stroke
				(width 0.1524)
				(type default)
			)
			(layer "F.SilkS")
		)
		(fp_line
			(start -0.67945 -0.305054)
			(end -0.12065 -0.305054)
			(stroke
				(width 0.1)
				(type default)
			)
			(layer "F.Fab")
		)
		(fp_line
			(start -0.67945 0.3048)
			(end -0.67945 -0.305054)
			(stroke
				(width 0.1)
				(type default)
			)
			(layer "F.Fab")
		)
		(fp_line
			(start -0.12065 -0.305054)
			(end -0.12065 -0.2794)
			(stroke
				(width 0.1)
				(type default)
			)
			(layer "F.Fab")
		)
		(fp_line
			(start -0.12065 -0.2794)
			(end 0.12065 -0.2794)
			(stroke
				(width 0.1)
				(type default)
			)
			(layer "F.Fab")
		)
		(fp_line
			(start -0.12065 0.2794)
			(end -0.12065 0.3048)
			(stroke
				(width 0.1)
				(type default)
			)
			(layer "F.Fab")
		)
		(fp_line
			(start -0.12065 0.3048)
			(end -0.67945 0.3048)
			(stroke
				(width 0.1)
				(type default)
			)
			(layer "F.Fab")
		)
		(fp_line
			(start 0.120396 0.2794)
			(end -0.12065 0.2794)
			(stroke
				(width 0.1)
				(type default)
			)
			(layer "F.Fab")
		)
		(fp_line
			(start 0.120396 0.3048)
			(end 0.120396 0.2794)
			(stroke
				(width 0.1)
				(type default)
			)
			(layer "F.Fab")
		)
		(fp_line
			(start 0.12065 -0.3048)
			(end 0.67945 -0.3048)
			(stroke
				(width 0.1)
				(type default)
			)
			(layer "F.Fab")
		)
		(fp_line
			(start 0.12065 -0.2794)
			(end 0.12065 -0.3048)
			(stroke
				(width 0.1)
				(type default)
			)
			(layer "F.Fab")
		)
		(fp_line
			(start 0.67945 -0.3048)
			(end 0.67945 0.3048)
			(stroke
				(width 0.1)
				(type default)
			)
			(layer "F.Fab")
		)
		(fp_line
			(start 0.67945 0.3048)
			(end 0.120396 0.3048)
			(stroke
				(width 0.1)
				(type default)
			)
			(layer "F.Fab")
		)
		(pad "1" smd circle
			(at -0.40005 0)
			(size 0 0)
			(layers "F.Cu" "F.Mask" "F.Paste")
			(net "U206_VDD")
		)
		(pad "2" smd circle
			(at 0.40005 0)
			(size 0 0)
			(layers "F.Cu" "F.Mask" "F.Paste")
			(net "GND")
		)
	)
	(footprint ""
		(layer "F.Cu")
		(at 354.261928 -258.726686 90)
		(property "Reference" "C966"
			(at 0 0 90)
			(layer "F.SilkS")
			(hide yes)
			(effects
				(font
					(size 1.27 1.27)
				)
			)
		)
		(property "Value" ""
			(at 0 0 90)
			(layer "F.Fab")
			(effects
				(font
					(size 1.27 1.27)
				)
			)
		)
		(duplicate_pad_numbers_are_jumpers no)
		(fp_line
			(start 0.7874 -0.4064)
			(end 0.7874 0.4064)
			(stroke
				(width 0.1524)
				(type default)
			)
			(layer "F.SilkS")
		)
		(fp_line
			(start -0.7874 -0.4064)
			(end 0.7874 -0.4064)
			(stroke
				(width 0.1524)
				(type default)
			)
			(layer "F.SilkS")
		)
		(fp_line
			(start 0.7874 0.4064)
			(end -0.7874 0.4064)
			(stroke
				(width 0.1524)
				(type default)
			)
			(layer "F.SilkS")
		)
		(fp_line
			(start -0.7874 0.4064)
			(end -0.7874 -0.4064)
			(stroke
				(width 0.1524)
				(type default)
			)
			(layer "F.SilkS")
		)
		(fp_line
			(start -0.12065 -0.305054)
			(end -0.12065 -0.2794)
			(stroke
				(width 0.1)
				(type default)
			)
			(layer "F.Fab")
		)
		(fp_line
			(start -0.67945 -0.305054)
			(end -0.12065 -0.305054)
			(stroke
				(width 0.1)
				(type default)
			)
			(layer "F.Fab")
		)
		(fp_line
			(start 0.67945 -0.3048)
			(end 0.67945 0.3048)
			(stroke
				(width 0.1)
				(type default)
			)
			(layer "F.Fab")
		)
		(fp_line
			(start 0.12065 -0.3048)
			(end 0.67945 -0.3048)
			(stroke
				(width 0.1)
				(type default)
			)
			(layer "F.Fab")
		)
		(fp_line
			(start 0.12065 -0.2794)
			(end 0.12065 -0.3048)
			(stroke
				(width 0.1)
				(type default)
			)
			(layer "F.Fab")
		)
		(fp_line
			(start -0.12065 -0.2794)
			(end 0.12065 -0.2794)
			(stroke
				(width 0.1)
				(type default)
			)
			(layer "F.Fab")
		)
		(fp_line
			(start 0.120396 0.2794)
			(end -0.12065 0.2794)
			(stroke
				(width 0.1)
				(type default)
			)
			(layer "F.Fab")
		)
		(fp_line
			(start -0.12065 0.2794)
			(end -0.12065 0.3048)
			(stroke
				(width 0.1)
				(type default)
			)
			(layer "F.Fab")
		)
		(fp_line
			(start 0.67945 0.3048)
			(end 0.120396 0.3048)
			(stroke
				(width 0.1)
				(type default)
			)
			(layer "F.Fab")
		)
		(fp_line
			(start 0.120396 0.3048)
			(end 0.120396 0.2794)
			(stroke
				(width 0.1)
				(type default)
			)
			(layer "F.Fab")
		)
		(fp_line
			(start -0.12065 0.3048)
			(end -0.67945 0.3048)
			(stroke
				(width 0.1)
				(type default)
			)
			(layer "F.Fab")
		)
		(fp_line
			(start -0.67945 0.3048)
			(end -0.67945 -0.305054)
			(stroke
				(width 0.1)
				(type default)
			)
			(layer "F.Fab")
		)
		(pad "1" smd circle
			(at -0.40005 0 90)
			(size 0 0)
			(layers "F.Cu" "F.Mask" "F.Paste")
			(net "PVCCIN_CPU0")
		)
		(pad "2" smd circle
			(at 0.40005 0 90)
			(size 0 0)
			(layers "F.Cu" "F.Mask" "F.Paste")
			(net "GND")
		)
	)
)
